(kicad_pcb
	(version 20260206)
	(generator "pcbnew")
	(generator_version "10.0")
	(general
		(thickness 1.6)
		(legacy_teardrops no)
	)
	(paper "A4")
	(title_block
		(title "Wiwynn_Tioga_Pass_MB.brd")
		(comment 1 "Tioga Pass / footprints 3967-3974 of 4770")
	)
	(layers
		(0 "F.Cu" signal "TOP")
		(4 "In1.Cu" signal "L2GND")
		(6 "In2.Cu" signal "L3")
		(8 "In3.Cu" signal "L4GND")
		(10 "In4.Cu" signal "L5")
		(12 "In5.Cu" signal "L6GND")
		(14 "In6.Cu" signal "L7VCC")
		(16 "In7.Cu" signal "L8VCC")
		(18 "In8.Cu" signal "L9GND")
		(20 "In9.Cu" signal "L10")
		(22 "In10.Cu" signal "L11GND")
		(24 "In11.Cu" signal "L12")
		(26 "In12.Cu" signal "L13GND")
		(2 "B.Cu" signal "BOTTOM")
		(9 "F.Adhes" user "F.Adhesive")
		(11 "B.Adhes" user "B.Adhesive")
		(13 "F.Paste" user "Package Geometry/Pastemask Top")
		(15 "B.Paste" user "Package Geometry/Pastemask Bottom")
		(5 "F.SilkS" user "Ref Des/Silkscreen Top")
		(7 "B.SilkS" user "Ref Des/Silkscreen Bottom")
		(1 "F.Mask" user "Board Geometry/Soldermask Top")
		(3 "B.Mask" user "Board Geometry/Soldermask Bottom")
		(17 "Dwgs.User" user "User.Drawings")
		(19 "Cmts.User" user "User.Comments")
		(21 "Eco1.User" user "User.Eco1")
		(23 "Eco2.User" user "User.Eco2")
		(25 "Edge.Cuts" user "Board Geometry/Outline")
		(27 "Margin" user)
		(31 "F.CrtYd" user "Package Geometry/Place Bound Top")
		(29 "B.CrtYd" user "Package Geometry/Place Bound Bottom")
		(35 "F.Fab" user "Ref Des/Assembly Top")
		(33 "B.Fab" user "Ref Des/Assembly Bottom")
	)
	(footprint ""
		(layer "B.Cu")
		(at 450.2277 -149.3774 -90)
		(property "Reference" "R25W165"
			(at 0.8382 -0.67818 270)
			(unlocked yes)
			(layer "B.SilkS")
			(effects
				(font
					(size 0.4064 0.254)
					(thickness 0.1524)
				)
				(justify left mirror)
			)
		)
		(property "Value" ""
			(at 0 0 90)
			(layer "B.Fab")
			(effects
				(font
					(size 1.27 1.27)
				)
				(justify mirror)
			)
		)
		(duplicate_pad_numbers_are_jumpers no)
		(fp_poly
			(pts
				(xy 0.2794 -0.1016) (xy -0.2794 -0.1016) (xy -0.2794 0.9906) (xy 0.2794 0.9906)
			)
			(stroke
				(width 0)
				(type default)
			)
			(fill no)
			(layer "B.CrtYd")
		)
		(fp_line
			(start -0.2794 0.9906)
			(end -0.2794 -0.1016)
			(stroke
				(width 0.1)
				(type default)
			)
			(layer "B.Fab")
		)
		(fp_line
			(start 0.2794 0.9906)
			(end -0.2794 0.9906)
			(stroke
				(width 0.1)
				(type default)
			)
			(layer "B.Fab")
		)
		(fp_line
			(start -0.2794 -0.1016)
			(end 0.2794 -0.1016)
			(stroke
				(width 0.1)
				(type default)
			)
			(layer "B.Fab")
		)
		(fp_line
			(start 0.2794 -0.1016)
			(end 0.2794 0.9906)
			(stroke
				(width 0.1)
				(type default)
			)
			(layer "B.Fab")
		)
		(pad "1" smd rect
			(at 0 0 90)
			(size 0.508 0.508)
			(layers "B.Cu" "B.Mask" "B.Paste")
			(net "P0V7_GTL2014_VREF_6")
		)
		(pad "2" smd rect
			(at 0 0.889 90)
			(size 0.508 0.508)
			(layers "B.Cu" "B.Mask" "B.Paste")
			(net "GND")
		)
		(zone
			(layer "B.Cu")
			(hatch none 0.5)
			(connect_pads
				(clearance 0)
			)
			(min_thickness 0.25)
			(keepout
				(tracks not_allowed)
				(vias allowed)
				(pads allowed)
				(copperpour not_allowed)
				(footprints allowed)
			)
			(placement
				(enabled no)
				(sheetname "")
			)
			(fill
				(thermal_gap 0.5)
				(thermal_bridge_width 0.5)
				(island_removal_mode 0)
			)
			(polygon
				(pts
					(xy 449.5927 -149.1234) (xy 449.5927 -149.6314) (xy 449.9737 -149.6314) (xy 449.9737 -149.1234)
				)
			)
		)
		(zone
			(layer "B.Cu")
			(hatch none 0.5)
			(connect_pads
				(clearance 0)
			)
			(min_thickness 0.25)
			(keepout
				(tracks allowed)
				(vias not_allowed)
				(pads allowed)
				(copperpour not_allowed)
				(footprints allowed)
			)
			(placement
				(enabled no)
				(sheetname "")
			)
			(fill
				(thermal_gap 0.5)
				(thermal_bridge_width 0.5)
				(island_removal_mode 0)
			)
			(polygon
				(pts
					(xy 449.9737 -149.1234) (xy 449.9737 -149.6314) (xy 449.5927 -149.6314) (xy 449.5927 -149.1234)
				)
			)
		)
	)
	(footprint ""
		(layer "B.Cu")
		(at 210.847432 -78.867 -90)
		(property "Reference" "C6P14"
			(at -2.00533 -3.909568 0)
			(unlocked yes)
			(layer "B.SilkS")
			(effects
				(font
					(size 0.7874 0.5842)
					(thickness 0.1524)
				)
				(justify mirror)
			)
		)
		(property "Value" ""
			(at 0 0 90)
			(layer "B.Fab")
			(effects
				(font
					(size 1.27 1.27)
				)
				(justify mirror)
			)
		)
		(duplicate_pad_numbers_are_jumpers no)
		(fp_line
			(start -2.286 7.366)
			(end -1.600708 7.366)
			(stroke
				(width 0.1524)
				(type default)
			)
			(layer "B.SilkS")
		)
		(fp_line
			(start -2.286 7.366)
			(end -2.286 1.63195)
			(stroke
				(width 0.1524)
				(type default)
			)
			(layer "B.SilkS")
		)
		(fp_line
			(start 2.286 7.366)
			(end 1.60147 7.366)
			(stroke
				(width 0.1524)
				(type default)
			)
			(layer "B.SilkS")
		)
		(fp_line
			(start 2.286 7.366)
			(end 2.286 1.632712)
			(stroke
				(width 0.1524)
				(type default)
			)
			(layer "B.SilkS")
		)
		(fp_line
			(start -2.504948 1.633728)
			(end -1.6002 1.633728)
			(stroke
				(width 0.1524)
				(type default)
			)
			(layer "B.SilkS")
		)
		(fp_line
			(start 2.563114 1.633728)
			(end 1.6002 1.633728)
			(stroke
				(width 0.1524)
				(type default)
			)
			(layer "B.SilkS")
		)
		(fp_line
			(start -2.504948 -1.616456)
			(end -2.504948 1.633728)
			(stroke
				(width 0.1524)
				(type default)
			)
			(layer "B.SilkS")
		)
		(fp_line
			(start -1.6002 -1.616456)
			(end -2.504948 -1.616456)
			(stroke
				(width 0.1524)
				(type default)
			)
			(layer "B.SilkS")
		)
		(fp_line
			(start 1.6002 -1.616456)
			(end 2.563114 -1.616456)
			(stroke
				(width 0.1524)
				(type default)
			)
			(layer "B.SilkS")
		)
		(fp_line
			(start 2.563114 -1.616456)
			(end 2.563114 1.633728)
			(stroke
				(width 0.1524)
				(type default)
			)
			(layer "B.SilkS")
		)
		(fp_rect
			(start 2.286 7.366)
			(end -2.286 -0.254)
			(stroke
				(width 0)
				(type default)
			)
			(fill no)
			(layer "B.CrtYd")
		)
		(fp_line
			(start -2.286 7.366)
			(end 2.286 7.366)
			(stroke
				(width 0.1)
				(type default)
			)
			(layer "B.Fab")
		)
		(fp_line
			(start 2.286 7.366)
			(end 2.286 -0.254)
			(stroke
				(width 0.1)
				(type default)
			)
			(layer "B.Fab")
		)
		(fp_line
			(start -2.286 -0.254)
			(end -2.286 7.366)
			(stroke
				(width 0.1)
				(type default)
			)
			(layer "B.Fab")
		)
		(fp_line
			(start 2.286 -0.254)
			(end -2.286 -0.254)
			(stroke
				(width 0.1)
				(type default)
			)
			(layer "B.Fab")
		)
		(pad "1" smd rect
			(at 0 0 90)
			(size 2.54 3.048)
			(layers "B.Cu" "B.Mask" "B.Paste")
			(net "PVCCIN_CPU0")
		)
		(pad "2" smd rect
			(at 0 7.112 90)
			(size 2.54 3.048)
			(layers "B.Cu" "B.Mask" "B.Paste")
			(net "GND")
		)
	)
	(footprint ""
		(layer "B.Cu")
		(at 348.57436 -77.788516)
		(property "Reference" "C3P24"
			(at 0 0 0)
			(layer "B.SilkS")
			(hide yes)
			(effects
				(font
					(size 1.27 1.27)
				)
				(justify mirror)
			)
		)
		(property "Value" ""
			(at 0 0 0)
			(layer "B.Fab")
			(effects
				(font
					(size 1.27 1.27)
				)
				(justify mirror)
			)
		)
		(duplicate_pad_numbers_are_jumpers no)
		(fp_poly
			(pts
				(xy -0.3048 -0.1016) (xy -0.3048 0.9906) (xy 0.3048 0.9906) (xy 0.3048 -0.1016)
			)
			(stroke
				(width 0)
				(type default)
			)
			(fill no)
			(layer "B.CrtYd")
		)
		(fp_line
			(start -0.3048 -0.1016)
			(end 0.3048 -0.1016)
			(stroke
				(width 0.1)
				(type default)
			)
			(layer "B.Fab")
		)
		(fp_line
			(start -0.3048 0.9906)
			(end -0.3048 -0.1016)
			(stroke
				(width 0.1)
				(type default)
			)
			(layer "B.Fab")
		)
		(fp_line
			(start 0.3048 -0.1016)
			(end 0.3048 0.9906)
			(stroke
				(width 0.1)
				(type default)
			)
			(layer "B.Fab")
		)
		(fp_line
			(start 0.3048 0.9906)
			(end -0.3048 0.9906)
			(stroke
				(width 0.1)
				(type default)
			)
			(layer "B.Fab")
		)
		(pad "1" smd rect
			(at 0 0 180)
			(size 0.508 0.508)
			(layers "B.Cu" "B.Mask" "B.Paste")
			(net "P3E_CPU0_PE1_SS_TXN<3>")
		)
		(pad "2" smd rect
			(at 0 0.889 180)
			(size 0.508 0.508)
			(layers "B.Cu" "B.Mask" "B.Paste")
			(net "P3E_CPU0_PE1_SS_C_TXN<3>")
		)
		(zone
			(layer "B.Cu")
			(hatch none 0.5)
			(connect_pads
				(clearance 0)
			)
			(min_thickness 0.25)
			(keepout
				(tracks allowed)
				(vias not_allowed)
				(pads allowed)
				(copperpour not_allowed)
				(footprints allowed)
			)
			(placement
				(enabled no)
				(sheetname "")
			)
			(fill
				(thermal_gap 0.5)
				(thermal_bridge_width 0.5)
				(island_removal_mode 0)
			)
			(polygon
				(pts
					(xy 348.82836 -77.534516) (xy 348.32036 -77.534516) (xy 348.32036 -77.153516) (xy 348.82836 -77.153516)
				)
			)
		)
		(zone
			(layer "B.Cu")
			(hatch none 0.5)
			(connect_pads
				(clearance 0)
			)
			(min_thickness 0.25)
			(keepout
				(tracks not_allowed)
				(vias allowed)
				(pads allowed)
				(copperpour not_allowed)
				(footprints allowed)
			)
			(placement
				(enabled no)
				(sheetname "")
			)
			(fill
				(thermal_gap 0.5)
				(thermal_bridge_width 0.5)
				(island_removal_mode 0)
			)
			(polygon
				(pts
					(xy 348.82836 -77.153516) (xy 348.32036 -77.153516) (xy 348.32036 -77.534516) (xy 348.82836 -77.534516)
				)
			)
		)
	)
	(footprint ""
		(layer "B.Cu")
		(at 397.002 -85.0265 180)
		(property "Reference" "R8D15"
			(at 0.8382 -0.67818 180)
			(unlocked yes)
			(layer "B.SilkS")
			(effects
				(font
					(size 0.4064 0.254)
					(thickness 0.1524)
				)
				(justify left mirror)
			)
		)
		(property "Value" ""
			(at 0 0 0)
			(layer "B.Fab")
			(effects
				(font
					(size 1.27 1.27)
				)
				(justify mirror)
			)
		)
		(duplicate_pad_numbers_are_jumpers no)
		(fp_poly
			(pts
				(xy 0.2794 -0.1016) (xy -0.2794 -0.1016) (xy -0.2794 0.9906) (xy 0.2794 0.9906)
			)
			(stroke
				(width 0)
				(type default)
			)
			(fill no)
			(layer "B.CrtYd")
		)
		(fp_line
			(start 0.2794 0.9906)
			(end -0.2794 0.9906)
			(stroke
				(width 0.1)
				(type default)
			)
			(layer "B.Fab")
		)
		(fp_line
			(start 0.2794 -0.1016)
			(end 0.2794 0.9906)
			(stroke
				(width 0.1)
				(type default)
			)
			(layer "B.Fab")
		)
		(fp_line
			(start -0.2794 0.9906)
			(end -0.2794 -0.1016)
			(stroke
				(width 0.1)
				(type default)
			)
			(layer "B.Fab")
		)
		(fp_line
			(start -0.2794 -0.1016)
			(end 0.2794 -0.1016)
			(stroke
				(width 0.1)
				(type default)
			)
			(layer "B.Fab")
		)
		(pad "1" smd rect
			(at 0 0)
			(size 0.508 0.508)
			(layers "B.Cu" "B.Mask" "B.Paste")
			(net "P3V3_STBY")
		)
		(pad "2" smd rect
			(at 0 0.889)
			(size 0.508 0.508)
			(layers "B.Cu" "B.Mask" "B.Paste")
			(net "SMB_VR_STBY_LVC3_SCL")
		)
		(zone
			(layer "B.Cu")
			(hatch none 0.5)
			(connect_pads
				(clearance 0)
			)
			(min_thickness 0.25)
			(keepout
				(tracks not_allowed)
				(vias allowed)
				(pads allowed)
				(copperpour not_allowed)
				(footprints allowed)
			)
			(placement
				(enabled no)
				(sheetname "")
			)
			(fill
				(thermal_gap 0.5)
				(thermal_bridge_width 0.5)
				(island_removal_mode 0)
			)
			(polygon
				(pts
					(xy 396.748 -85.6615) (xy 397.256 -85.6615) (xy 397.256 -85.2805) (xy 396.748 -85.2805)
				)
			)
		)
		(zone
			(layer "B.Cu")
			(hatch none 0.5)
			(connect_pads
				(clearance 0)
			)
			(min_thickness 0.25)
			(keepout
				(tracks allowed)
				(vias not_allowed)
				(pads allowed)
				(copperpour not_allowed)
				(footprints allowed)
			)
			(placement
				(enabled no)
				(sheetname "")
			)
			(fill
				(thermal_gap 0.5)
				(thermal_bridge_width 0.5)
				(island_removal_mode 0)
			)
			(polygon
				(pts
					(xy 396.748 -85.2805) (xy 397.256 -85.2805) (xy 397.256 -85.6615) (xy 396.748 -85.6615)
				)
			)
		)
	)
	(footprint ""
		(layer "B.Cu")
		(at 365.001302 -145.471642)
		(property "Reference" "C7W6"
			(at 0 0 0)
			(layer "B.SilkS")
			(hide yes)
			(effects
				(font
					(size 1.27 1.27)
				)
				(justify mirror)
			)
		)
		(property "Value" "*"
			(at 0.0762 -6.2357 0)
			(unlocked yes)
			(layer "B.Fab")
			(hide yes)
			(effects
				(font
					(size 1.27 1.016)
					(thickness 0.1524)
				)
				(justify mirror)
			)
		)
		(property "Device Type" "SC22U16V5MX-4-GP_SMD-BCG5-SC22A"
			(at 0.0762 -8.2677 0)
			(unlocked yes)
			(layer "B.Fab")
			(hide yes)
			(effects
				(font
					(size 1.27 1.016)
					(thickness 0.1524)
				)
				(justify mirror)
			)
		)
		(duplicate_pad_numbers_are_jumpers no)
		(fp_line
			(start -0.635 0)
			(end 0.635 0)
			(stroke
				(width 0.508)
				(type default)
			)
			(layer "B.SilkS")
		)
		(fp_rect
			(start 0.9652 1.778)
			(end -0.9652 -1.778)
			(stroke
				(width 0)
				(type default)
			)
			(fill no)
			(layer "B.CrtYd")
		)
		(fp_poly
			(pts
				(xy 0.9652 -1.778) (xy -0.9652 -1.778) (xy -0.9652 1.778) (xy 0.9652 1.778)
			)
			(stroke
				(width 0)
				(type default)
			)
			(fill no)
			(layer "B.Fab")
		)
		(pad "1" smd rect
			(at 0 -0.9652 180)
			(size 1.397 1.143)
			(layers "B.Cu" "B.Mask" "B.Paste")
			(net "VR_FET_SW_P12V_STBY_PVDDQ_DEF")
		)
		(pad "2" smd rect
			(at 0 0.9652 180)
			(size 1.397 1.143)
			(layers "B.Cu" "B.Mask" "B.Paste")
			(net "GND")
		)
	)
	(footprint ""
		(layer "B.Cu")
		(at 197.848728 -90.838782 90)
		(property "Reference" "C6N10"
			(at 0 0 90)
			(layer "B.SilkS")
			(hide yes)
			(effects
				(font
					(size 1.27 1.27)
				)
				(justify mirror)
			)
		)
		(property "Value" ""
			(at 0 0 90)
			(layer "B.Fab")
			(effects
				(font
					(size 1.27 1.27)
				)
				(justify mirror)
			)
		)
		(duplicate_pad_numbers_are_jumpers no)
		(fp_rect
			(start 0.7239 1.9939)
			(end -0.7239 -0.2159)
			(stroke
				(width 0)
				(type default)
			)
			(fill no)
			(layer "B.CrtYd")
		)
		(fp_line
			(start 0.7239 -0.2159)
			(end 0.7239 1.9939)
			(stroke
				(width 0.1)
				(type default)
			)
			(layer "B.Fab")
		)
		(fp_line
			(start -0.7239 -0.2159)
			(end 0.7239 -0.2159)
			(stroke
				(width 0.1)
				(type default)
			)
			(layer "B.Fab")
		)
		(fp_line
			(start 0.7239 1.9939)
			(end -0.7239 1.9939)
			(stroke
				(width 0.1)
				(type default)
			)
			(layer "B.Fab")
		)
		(fp_line
			(start -0.7239 1.9939)
			(end -0.7239 -0.2159)
			(stroke
				(width 0.1)
				(type default)
			)
			(layer "B.Fab")
		)
		(pad "1" smd rect
			(at 0 0 270)
			(size 1.27 1.016)
			(layers "B.Cu" "B.Mask" "B.Paste")
			(net "VR_FET_SW_P12V_STBY_PVCCIN_CPU0")
		)
		(pad "2" smd rect
			(at 0 1.778 270)
			(size 1.27 1.016)
			(layers "B.Cu" "B.Mask" "B.Paste")
			(net "GND")
		)
		(zone
			(layer "B.Cu")
			(hatch none 0.5)
			(connect_pads
				(clearance 0)
			)
			(min_thickness 0.25)
			(keepout
				(tracks not_allowed)
				(vias allowed)
				(pads allowed)
				(copperpour not_allowed)
				(footprints allowed)
			)
			(placement
				(enabled no)
				(sheetname "")
			)
			(fill
				(thermal_gap 0.5)
				(thermal_bridge_width 0.5)
				(island_removal_mode 0)
			)
			(polygon
				(pts
					(xy 199.118728 -91.473782) (xy 198.356728 -91.473782) (xy 198.356728 -90.203782) (xy 199.118728 -90.203782)
				)
			)
		)
	)
	(footprint ""
		(layer "B.Cu")
		(at 345.832176 -77.694536 180)
		(property "Reference" "C3P20"
			(at 0 0 0)
			(layer "B.SilkS")
			(hide yes)
			(effects
				(font
					(size 1.27 1.27)
				)
				(justify mirror)
			)
		)
		(property "Value" ""
			(at 0 0 0)
			(layer "B.Fab")
			(effects
				(font
					(size 1.27 1.27)
				)
				(justify mirror)
			)
		)
		(duplicate_pad_numbers_are_jumpers no)
		(fp_poly
			(pts
				(xy -0.3048 -0.1016) (xy -0.3048 0.9906) (xy 0.3048 0.9906) (xy 0.3048 -0.1016)
			)
			(stroke
				(width 0)
				(type default)
			)
			(fill no)
			(layer "B.CrtYd")
		)
		(fp_line
			(start 0.3048 0.9906)
			(end -0.3048 0.9906)
			(stroke
				(width 0.1)
				(type default)
			)
			(layer "B.Fab")
		)
		(fp_line
			(start 0.3048 -0.1016)
			(end 0.3048 0.9906)
			(stroke
				(width 0.1)
				(type default)
			)
			(layer "B.Fab")
		)
		(fp_line
			(start -0.3048 0.9906)
			(end -0.3048 -0.1016)
			(stroke
				(width 0.1)
				(type default)
			)
			(layer "B.Fab")
		)
		(fp_line
			(start -0.3048 -0.1016)
			(end 0.3048 -0.1016)
			(stroke
				(width 0.1)
				(type default)
			)
			(layer "B.Fab")
		)
		(pad "1" smd rect
			(at 0 0)
			(size 0.508 0.508)
			(layers "B.Cu" "B.Mask" "B.Paste")
			(net "P3E_CPU0_PE1_SS_TXN<2>")
		)
		(pad "2" smd rect
			(at 0 0.889)
			(size 0.508 0.508)
			(layers "B.Cu" "B.Mask" "B.Paste")
			(net "P3E_CPU0_PE1_PCH_TXN<2>")
		)
		(zone
			(layer "B.Cu")
			(hatch none 0.5)
			(connect_pads
				(clearance 0)
			)
			(min_thickness 0.25)
			(keepout
				(tracks allowed)
				(vias not_allowed)
				(pads allowed)
				(copperpour not_allowed)
				(footprints allowed)
			)
			(placement
				(enabled no)
				(sheetname "")
			)
			(fill
				(thermal_gap 0.5)
				(thermal_bridge_width 0.5)
				(island_removal_mode 0)
			)
			(polygon
				(pts
					(xy 345.578176 -77.948536) (xy 346.086176 -77.948536) (xy 346.086176 -78.329536) (xy 345.578176 -78.329536)
				)
			)
		)
	)
	(footprint ""
		(layer "B.Cu")
		(at 490.9058 -51.64709 180)
		(property "Reference" "C25P83"
			(at 0.8382 -0.67818 180)
			(unlocked yes)
			(layer "B.SilkS")
			(effects
				(font
					(size 0.4064 0.254)
					(thickness 0.1524)
				)
				(justify left mirror)
			)
		)
		(property "Value" ""
			(at 0 0 0)
			(layer "B.Fab")
			(effects
				(font
					(size 1.27 1.27)
				)
				(justify mirror)
			)
		)
		(duplicate_pad_numbers_are_jumpers no)
		(fp_poly
			(pts
				(xy -0.3048 -0.1016) (xy -0.3048 0.9906) (xy 0.3048 0.9906) (xy 0.3048 -0.1016)
			)
			(stroke
				(width 0)
				(type default)
			)
			(fill no)
			(layer "B.CrtYd")
		)
		(fp_line
			(start 0.3048 0.9906)
			(end -0.3048 0.9906)
			(stroke
				(width 0.1)
				(type default)
			)
			(layer "B.Fab")
		)
		(fp_line
			(start 0.3048 -0.1016)
			(end 0.3048 0.9906)
			(stroke
				(width 0.1)
				(type default)
			)
			(layer "B.Fab")
		)
		(fp_line
			(start -0.3048 0.9906)
			(end -0.3048 -0.1016)
			(stroke
				(width 0.1)
				(type default)
			)
			(layer "B.Fab")
		)
		(fp_line
			(start -0.3048 -0.1016)
			(end 0.3048 -0.1016)
			(stroke
				(width 0.1)
				(type default)
			)
			(layer "B.Fab")
		)
		(pad "1" smd rect
			(at 0 0)
			(size 0.508 0.508)
			(layers "B.Cu" "B.Mask" "B.Paste")
			(net "P5V_VGA")
		)
		(pad "2" smd rect
			(at 0 0.889)
			(size 0.508 0.508)
			(layers "B.Cu" "B.Mask" "B.Paste")
			(net "GND")
		)
		(zone
			(layer "B.Cu")
			(hatch none 0.5)
			(connect_pads
				(clearance 0)
			)
			(min_thickness 0.25)
			(keepout
				(tracks not_allowed)
				(vias allowed)
				(pads allowed)
				(copperpour not_allowed)
				(footprints allowed)
			)
			(placement
				(enabled no)
				(sheetname "")
			)
			(fill
				(thermal_gap 0.5)
				(thermal_bridge_width 0.5)
				(island_removal_mode 0)
			)
			(polygon
				(pts
					(xy 490.6518 -52.28209) (xy 491.1598 -52.28209) (xy 491.1598 -51.90109) (xy 490.6518 -51.90109)
				)
			)
		)
		(zone
			(layer "B.Cu")
			(hatch none 0.5)
			(connect_pads
				(clearance 0)
			)
			(min_thickness 0.25)
			(keepout
				(tracks allowed)
				(vias not_allowed)
				(pads allowed)
				(copperpour not_allowed)
				(footprints allowed)
			)
			(placement
				(enabled no)
				(sheetname "")
			)
			(fill
				(thermal_gap 0.5)
				(thermal_bridge_width 0.5)
				(island_removal_mode 0)
			)
			(polygon
				(pts
					(xy 490.6518 -51.90109) (xy 491.1598 -51.90109) (xy 491.1598 -52.28209) (xy 490.6518 -52.28209)
				)
			)
		)
	)
)
